FILE_TYPE = CONNECTIVITY;
{Allegro Design Entry HDL 17.4-2019 S026 (4007227) 1/17/2022}
"PAGE_NUMBER" = 461;
0"NC";
1"P5E_CPU1_P3_TX_BUF_C_DN<7:0>";
2"P5E_CPU1_P3_TX_BUF_DN<7:0>";
3"P5E_CPU1_P3_TX_BUF_DP<7:0>";
4"P5E_CPU1_P3_TX_BUF_C_DP<7:0>";
5"P5E_CPU1_P3_TX_BUF_DN<15:8>";
6"P5E_CPU1_P3_TX_BUF_DP<15:8>";
7"P5E_CPU1_P3_TX_BUF_C_DN<15:8>";
8"P5E_CPU1_P3_TX_BUF_C_DP<15:8>";
9"P5E_CPU1_P3_TX_BUF_DN<7:0>";
10"P5E_CPU1_P3_TX_BUF_DP<7:0>";
11"P5E_CPU1_P3_TX_BUF_DN<15:8>";
12"P5E_CPU1_P3_TX_BUF_DP<15:8>";
13"P5E_CPU1_P3_TX_BUF_DN<9>";
14"P5E_CPU1_P3_TX_BUF_DP<9>";
15"P5E_CPU1_P3_TX_BUF_DP<11>";
16"P5E_CPU1_P3_TX_BUF_DN<15>";
17"P5E_CPU1_P3_TX_BUF_DP<15>";
18"P5E_CPU1_P3_TX_BUF_DP<13>";
19"P5E_CPU1_P3_TX_BUF_DP<10>";
20"P5E_CPU1_P3_TX_BUF_DN<2>";
21"P5E_CPU1_P3_TX_BUF_DN<1>";
22"P5E_CPU1_P3_TX_BUF_DN<0>";
23"P5E_CPU1_P3_TX_BUF_DP<1>";
24"P5E_CPU1_P3_TX_BUF_DP<2>";
25"P5E_CPU1_P3_TX_BUF_DP<7>";
26"P5E_CPU1_P3_TX_BUF_DP<4>";
27"P5E_CPU1_P3_TX_BUF_DP<3>";
28"P5E_CPU1_P3_TX_BUF_DN<4>";
29"P5E_CPU1_P3_TX_BUF_DN<13>";
30"P5E_CPU1_P3_TX_BUF_DN<14>";
31"P5E_CPU1_P3_TX_BUF_DP<14>";
32"P5E_CPU1_P3_TX_BUF_DP<8>";
33"P5E_CPU1_P3_TX_BUF_DN<10>";
34"P5E_CPU1_P3_TX_BUF_DN<11>";
35"P5E_CPU1_P3_TX_BUF_DN<12>";
36"P5E_CPU1_P3_TX_BUF_DP<12>";
37"P5E_CPU1_P3_TX_BUF_DN<8>";
38"P5E_CPU1_P3_TX_BUF_DN<7>";
39"P5E_CPU1_P3_TX_BUF_DP<0>";
40"P5E_CPU1_P3_TX_BUF_DN<3>";
41"P5E_CPU1_P3_TX_BUF_DN<5>";
42"P5E_CPU1_P3_TX_BUF_DP<5>";
43"P5E_CPU1_P3_TX_BUF_DP<6>";
44"P5E_CPU1_P3_TX_BUF_DN<6>";
45"P5E_CPU1_P3_TX_BUF_C_DP<8>";
46"P5E_CPU1_P3_TX_BUF_DP<8>";
47"P5E_CPU1_P3_TX_BUF_C_DN<8>";
48"P5E_CPU1_P3_TX_BUF_DN<8>";
49"P5E_CPU1_P3_TX_BUF_C_DP<9>";
50"P5E_CPU1_P3_TX_BUF_C_DN<9>";
51"P5E_CPU1_P3_TX_BUF_C_DP<10>";
52"P5E_CPU1_P3_TX_BUF_C_DN<10>";
53"P5E_CPU1_P3_TX_BUF_C_DN<11>";
54"P5E_CPU1_P3_TX_BUF_C_DP<11>";
55"P5E_CPU1_P3_TX_BUF_C_DP<12>";
56"P5E_CPU1_P3_TX_BUF_C_DN<12>";
57"P5E_CPU1_P3_TX_BUF_C_DP<13>";
58"P5E_CPU1_P3_TX_BUF_C_DN<13>";
59"P5E_CPU1_P3_TX_BUF_C_DP<14>";
60"P5E_CPU1_P3_TX_BUF_C_DN<14>";
61"P5E_CPU1_P3_TX_BUF_C_DP<15>";
62"P5E_CPU1_P3_TX_BUF_C_DN<15>";
63"P5E_CPU1_P3_TX_BUF_DP<9>";
64"P5E_CPU1_P3_TX_BUF_DP<10>";
65"P5E_CPU1_P3_TX_BUF_DN<9>";
66"P5E_CPU1_P3_TX_BUF_DN<10>";
67"P5E_CPU1_P3_TX_BUF_DP<11>";
68"P5E_CPU1_P3_TX_BUF_DP<12>";
69"P5E_CPU1_P3_TX_BUF_DP<13>";
70"P5E_CPU1_P3_TX_BUF_DN<12>";
71"P5E_CPU1_P3_TX_BUF_DN<13>";
72"P5E_CPU1_P3_TX_BUF_DN<11>";
73"P5E_CPU1_P3_TX_BUF_DP<14>";
74"P5E_CPU1_P3_TX_BUF_DP<15>";
75"P5E_CPU1_P3_TX_BUF_DN<14>";
76"P5E_CPU1_P3_TX_BUF_DN<15>";
77"P5E_CPU1_P3_TX_BUF_C_DP<0>";
78"P5E_CPU1_P3_TX_BUF_C_DN<0>";
79"P5E_CPU1_P3_TX_BUF_DP<0>";
80"P5E_CPU1_P3_TX_BUF_DN<0>";
81"P5E_CPU1_P3_TX_BUF_C_DP<1>";
82"P5E_CPU1_P3_TX_BUF_DP<1>";
83"P5E_CPU1_P3_TX_BUF_C_DN<1>";
84"P5E_CPU1_P3_TX_BUF_C_DP<2>";
85"P5E_CPU1_P3_TX_BUF_C_DN<2>";
86"P5E_CPU1_P3_TX_BUF_C_DP<3>";
87"P5E_CPU1_P3_TX_BUF_C_DP<4>";
88"P5E_CPU1_P3_TX_BUF_C_DN<4>";
89"P5E_CPU1_P3_TX_BUF_C_DN<5>";
90"P5E_CPU1_P3_TX_BUF_C_DP<5>";
91"P5E_CPU1_P3_TX_BUF_C_DP<6>";
92"P5E_CPU1_P3_TX_BUF_C_DN<6>";
93"P5E_CPU1_P3_TX_BUF_C_DP<7>";
94"P5E_CPU1_P3_TX_BUF_C_DN<7>";
95"P5E_CPU1_P3_TX_BUF_DP<2>";
96"P5E_CPU1_P3_TX_BUF_DP<3>";
97"P5E_CPU1_P3_TX_BUF_DP<4>";
98"P5E_CPU1_P3_TX_BUF_DP<5>";
99"P5E_CPU1_P3_TX_BUF_DP<6>";
100"P5E_CPU1_P3_TX_BUF_DN<2>";
101"P5E_CPU1_P3_TX_BUF_DN<1>";
102"P5E_CPU1_P3_TX_BUF_DN<3>";
103"P5E_CPU1_P3_TX_BUF_DN<4>";
104"P5E_CPU1_P3_TX_BUF_DN<5>";
105"P5E_CPU1_P3_TX_BUF_DP<7>";
106"P5E_CPU1_P3_TX_BUF_DN<6>";
107"P5E_CPU1_P3_TX_BUF_DN<7>";
108"P5E_CPU1_P3_TX_BUF_C_DN<3>";
%"TAP"
"1","(-3425,1975)","2","standard","I10";
;
CDS_LIB"standard"
BODY_TYPE"PLUMBING"
HDL_TAP"TRUE";
"B \NAC \NWC"2;
"S \NAC"
BN"1"101;
%"Q_CAP_DIFFBUS"
"2","(-7025,1850)","2","pure_quanta","I100";
;
LOCATION"C6744"
$SEC"1"
CDS_SEC"1"
VALUE"DIFF BUS_0.22UF"
TOLERANCE"20%"
PACK_TYPE"C0201"
MATERIAL"X6S"
VOLTAGE"6.3V"
PIN_NAMES_ROTATE"TRUE"
CDS_LIB"pure_quanta"
CDS_LMAN_SYM_OUTLINE"-25,50,25,-50"
PART_NUMBER"SP_CH4221MEE01"
LOCATION"C6744";
"2"
$PN"2"65;
"1"
$PN"1"50;
%"Q_CAP_DIFFBUS"
"2","(-7025,1900)","2","pure_quanta","I101";
;
LOCATION"C6743"
$SEC"1"
CDS_SEC"1"
VALUE"DIFF BUS_0.22UF"
TOLERANCE"20%"
PACK_TYPE"C0201"
MATERIAL"X6S"
VOLTAGE"6.3V"
PIN_NAMES_ROTATE"TRUE"
CDS_LIB"pure_quanta"
CDS_LMAN_SYM_OUTLINE"-25,50,25,-50"
PART_NUMBER"SP_CH4221MEE01"
LOCATION"C6743";
"2"
$PN"2"63;
"1"
$PN"1"49;
%"TAP"
"1","(-8000,2050)","2","standard","I102";
;
CDS_LIB"standard"
BODY_TYPE"PLUMBING"
HDL_TAP"TRUE";
"B \NAC \NWC"5;
"S \NAC"
BN"8"48;
%"TAP"
"1","(-7750,2100)","2","standard","I103";
;
CDS_LIB"standard"
BODY_TYPE"PLUMBING"
HDL_TAP"TRUE";
"B \NAC \NWC"6;
"S \NAC"
BN"8"46;
%"Q_CAP_DIFFBUS"
"2","(-7025,2050)","2","pure_quanta","I104";
;
LOCATION"C6742"
$SEC"1"
CDS_SEC"1"
VALUE"DIFF BUS_0.22UF"
TOLERANCE"20%"
PACK_TYPE"C0201"
MATERIAL"X6S"
VOLTAGE"6.3V"
PIN_NAMES_ROTATE"TRUE"
CDS_LIB"pure_quanta"
CDS_LMAN_SYM_OUTLINE"-25,50,25,-50"
PART_NUMBER"SP_CH4221MEE01"
LOCATION"C6742";
"2"
$PN"2"48;
"1"
$PN"1"47;
%"Q_CAP_DIFFBUS"
"2","(-7025,2100)","2","pure_quanta","I105";
;
LOCATION"C6741"
$SEC"1"
CDS_SEC"1"
VALUE"DIFF BUS_0.22UF"
TOLERANCE"20%"
PACK_TYPE"C0201"
MATERIAL"X6S"
VOLTAGE"6.3V"
PIN_NAMES_ROTATE"TRUE"
CDS_LMAN_SYM_OUTLINE"-25,50,25,-50"
CDS_LIB"pure_quanta"
PART_NUMBER"SP_CH4221MEE01"
LOCATION"C6741";
"2"
$PN"2"46;
"1"
$PN"1"45;
%"TAP"
"1","(-6475,700)","0","standard","I106";
;
CDS_LIB"standard"
BODY_TYPE"PLUMBING"
HDL_TAP"TRUE";
"B \NAC \NWC"8;
"S \NAC"
BN"15"61;
%"TAP"
"1","(-6475,900)","0","standard","I107";
;
CDS_LIB"standard"
BODY_TYPE"PLUMBING"
HDL_TAP"TRUE";
"B \NAC \NWC"8;
"S \NAC"
BN"14"59;
%"TAP"
"1","(-6275,650)","0","standard","I108";
;
CDS_LIB"standard"
BODY_TYPE"PLUMBING"
HDL_TAP"TRUE";
"B \NAC \NWC"7;
"S \NAC"
BN"15"62;
%"TAP"
"1","(-6275,850)","0","standard","I109";
;
CDS_LIB"standard"
BODY_TYPE"PLUMBING"
HDL_TAP"TRUE";
"B \NAC \NWC"7;
"S \NAC"
BN"14"60;
%"TAP"
"1","(-3175,1225)","2","standard","I11";
;
CDS_LIB"standard"
BODY_TYPE"PLUMBING"
HDL_TAP"TRUE";
"B \NAC \NWC"3;
"S \NAC"
BN"5"98;
%"TAP"
"1","(-6475,1100)","0","standard","I110";
;
CDS_LIB"standard"
BODY_TYPE"PLUMBING"
HDL_TAP"TRUE";
"B \NAC \NWC"8;
"S \NAC"
BN"13"57;
%"TAP"
"1","(-6475,1300)","0","standard","I111";
;
CDS_LIB"standard"
BODY_TYPE"PLUMBING"
HDL_TAP"TRUE";
"B \NAC \NWC"8;
"S \NAC"
BN"12"55;
%"TAP"
"1","(-6275,1050)","0","standard","I112";
;
CDS_LIB"standard"
BODY_TYPE"PLUMBING"
HDL_TAP"TRUE";
"B \NAC \NWC"7;
"S \NAC"
BN"13"58;
%"TAP"
"1","(-6275,1250)","0","standard","I113";
;
CDS_LIB"standard"
BODY_TYPE"PLUMBING"
HDL_TAP"TRUE";
"B \NAC \NWC"7;
"S \NAC"
BN"12"56;
%"TAP"
"1","(-6475,1500)","0","standard","I114";
;
CDS_LIB"standard"
BODY_TYPE"PLUMBING"
HDL_TAP"TRUE";
"B \NAC \NWC"8;
"S \NAC"
BN"11"54;
%"TAP"
"1","(-6475,1700)","0","standard","I115";
;
CDS_LIB"standard"
BODY_TYPE"PLUMBING"
HDL_TAP"TRUE";
"B \NAC \NWC"8;
"S \NAC"
BN"10"51;
%"TAP"
"1","(-6475,1900)","0","standard","I116";
;
CDS_LIB"standard"
BODY_TYPE"PLUMBING"
HDL_TAP"TRUE";
"B \NAC \NWC"8;
"S \NAC"
BN"9"49;
%"TAP"
"1","(-6275,1450)","0","standard","I117";
;
CDS_LIB"standard"
BODY_TYPE"PLUMBING"
HDL_TAP"TRUE";
"B \NAC \NWC"7;
"S \NAC"
BN"11"53;
%"TAP"
"1","(-6275,1650)","0","standard","I118";
;
CDS_LIB"standard"
BODY_TYPE"PLUMBING"
HDL_TAP"TRUE";
"B \NAC \NWC"7;
"S \NAC"
BN"10"52;
%"TAP"
"1","(-6275,1850)","0","standard","I119";
;
CDS_LIB"standard"
BODY_TYPE"PLUMBING"
HDL_TAP"TRUE";
"B \NAC \NWC"7;
"S \NAC"
BN"9"50;
%"TAP"
"1","(-3175,1025)","2","standard","I12";
;
CDS_LIB"standard"
BODY_TYPE"PLUMBING"
HDL_TAP"TRUE";
"B \NAC \NWC"3;
"S \NAC"
BN"6"99;
%"TAP"
"1","(-6475,2100)","0","standard","I120";
;
CDS_LIB"standard"
BODY_TYPE"PLUMBING"
HDL_TAP"TRUE";
"B \NAC \NWC"8;
"S \NAC"
BN"8"45;
%"TAP"
"1","(-6275,2050)","0","standard","I121";
;
CDS_LIB"standard"
BODY_TYPE"PLUMBING"
HDL_TAP"TRUE";
"B \NAC \NWC"7;
"S \NAC"
BN"8"47;
%"TAP"
"1","(-1875,3300)","0","standard","I122";
;
CDS_LIB"standard"
BODY_TYPE"PLUMBING"
HDL_TAP"TRUE";
"B \NAC \NWC"10;
"S \NAC"
BN"0"39;
%"TAP"
"1","(-1675,3200)","0","standard","I123";
;
CDS_LIB"standard"
BODY_TYPE"PLUMBING"
HDL_TAP"TRUE";
"B \NAC \NWC"9;
"S \NAC"
BN"0"22;
%"TAP"
"1","(-1875,3650)","0","standard","I124";
;
CDS_LIB"standard"
BODY_TYPE"PLUMBING"
HDL_TAP"TRUE";
"B \NAC \NWC"10;
"S \NAC"
BN"1"23;
%"TAP"
"1","(-1675,3550)","0","standard","I125";
;
CDS_LIB"standard"
BODY_TYPE"PLUMBING"
HDL_TAP"TRUE";
"B \NAC \NWC"9;
"S \NAC"
BN"1"21;
%"TAP"
"1","(-1675,3900)","0","standard","I126";
;
CDS_LIB"standard"
BODY_TYPE"PLUMBING"
HDL_TAP"TRUE";
"B \NAC \NWC"9;
"S \NAC"
BN"2"20;
%"TAP"
"1","(-1875,4000)","0","standard","I129";
;
CDS_LIB"standard"
BODY_TYPE"PLUMBING"
HDL_TAP"TRUE";
"B \NAC \NWC"10;
"S \NAC"
BN"2"24;
%"TAP"
"1","(-3175,1425)","2","standard","I13";
;
CDS_LIB"standard"
BODY_TYPE"PLUMBING"
HDL_TAP"TRUE";
"B \NAC \NWC"3;
"S \NAC"
BN"4"97;
%"TAP"
"1","(-1875,4350)","0","standard","I130";
;
CDS_LIB"standard"
BODY_TYPE"PLUMBING"
HDL_TAP"TRUE";
"B \NAC \NWC"10;
"S \NAC"
BN"3"27;
%"TAP"
"1","(-1675,4250)","0","standard","I131";
;
CDS_LIB"standard"
BODY_TYPE"PLUMBING"
HDL_TAP"TRUE";
"B \NAC \NWC"9;
"S \NAC"
BN"3"40;
%"TAP"
"1","(-1675,4600)","0","standard","I132";
;
CDS_LIB"standard"
BODY_TYPE"PLUMBING"
HDL_TAP"TRUE";
"B \NAC \NWC"9;
"S \NAC"
BN"4"28;
%"TAP"
"1","(-1675,4950)","0","standard","I133";
;
CDS_LIB"standard"
BODY_TYPE"PLUMBING"
HDL_TAP"TRUE";
"B \NAC \NWC"9;
"S \NAC"
BN"5"41;
%"TAP"
"1","(-1875,5050)","0","standard","I134";
;
CDS_LIB"standard"
BODY_TYPE"PLUMBING"
HDL_TAP"TRUE";
"B \NAC \NWC"10;
"S \NAC"
BN"5"42;
%"TAP"
"1","(-1875,5400)","0","standard","I135";
;
CDS_LIB"standard"
BODY_TYPE"PLUMBING"
HDL_TAP"TRUE";
"B \NAC \NWC"10;
"S \NAC"
BN"6"43;
%"TAP"
"1","(-1675,5300)","0","standard","I136";
;
CDS_LIB"standard"
BODY_TYPE"PLUMBING"
HDL_TAP"TRUE";
"B \NAC \NWC"9;
"S \NAC"
BN"6"44;
%"TAP"
"1","(-1875,5750)","0","standard","I137";
;
CDS_LIB"standard"
BODY_TYPE"PLUMBING"
HDL_TAP"TRUE";
"B \NAC \NWC"10;
"S \NAC"
BN"7"25;
%"TAP"
"1","(-1675,5650)","0","standard","I138";
;
CDS_LIB"standard"
BODY_TYPE"PLUMBING"
HDL_TAP"TRUE";
"B \NAC \NWC"9;
"S \NAC"
BN"7"38;
%"TAP"
"1","(-3175,1625)","2","standard","I14";
;
CDS_LIB"standard"
BODY_TYPE"PLUMBING"
HDL_TAP"TRUE";
"B \NAC \NWC"3;
"S \NAC"
BN"3"96;
%"TAP"
"1","(-1875,4700)","0","standard","I141";
;
CDS_LIB"standard"
BODY_TYPE"PLUMBING"
HDL_TAP"TRUE";
"B \NAC \NWC"10;
"S \NAC"
BN"4"26;
%"PT5161LRS"
"11","(-2600,4500)","0","pure_quanta","I142";
;
LOCATION"U6017"
$SEC"11"
CDS_SEC"11"
MATERIAL"IC"
VALUE"PT5161LRS"
PART_TYPE"SMLF"
NEEDS_NO_SIZE"TRUE"
CDS_LMAN_SYM_OUTLINE"-350,1450,300,-1400"
CDS_LIB"pure_quanta"
PART_NUMBER"AJ051610U03";
"B_PETN15"
$PN"EW10"22;
"B_PETP15"
$PN"EU7"39;
"B_PETN14"
$PN"EM10"21;
"B_PETP14"
$PN"EK7"23;
"B_PETN13"
$PN"EE10"20;
"B_PETP13"
$PN"EC7"24;
"B_PETN12"
$PN"DV10"40;
"B_PETP12"
$PN"DT7"27;
"B_PETN11"
$PN"DL10"28;
"B_PETP11"
$PN"DJ7"26;
"B_PETN10"
$PN"DD10"41;
"B_PETP10"
$PN"DB7"42;
"B_PETN9"
$PN"CU10"44;
"B_PETP9"
$PN"CR7"43;
"B_PETN8"
$PN"CK10"38;
"B_PETP8"
$PN"CH7"25;
%"TAP"
"1","(-3175,1825)","2","standard","I15";
;
CDS_LIB"standard"
BODY_TYPE"PLUMBING"
HDL_TAP"TRUE";
"B \NAC \NWC"3;
"S \NAC"
BN"2"95;
%"Q_CAP_DIFFBUS"
"2","(-2450,975)","2","pure_quanta","I16";
;
LOCATION"C6738"
$SEC"1"
CDS_SEC"1"
VALUE"DIFF BUS_0.22UF"
CDS_LMAN_SYM_OUTLINE"-25,50,25,-50"
CDS_LIB"pure_quanta"
PIN_NAMES_ROTATE"TRUE"
VOLTAGE"6.3V"
MATERIAL"X6S"
PACK_TYPE"C0201"
TOLERANCE"20%"
PART_NUMBER"SP_CH4221MEE01"
LOCATION"C6738";
"2"
$PN"2"106;
"1"
$PN"1"92;
%"Q_CAP_DIFFBUS"
"2","(-2450,825)","2","pure_quanta","I17";
;
LOCATION"C6739"
$SEC"1"
CDS_SEC"1"
VALUE"DIFF BUS_0.22UF"
CDS_LMAN_SYM_OUTLINE"-25,50,25,-50"
CDS_LIB"pure_quanta"
PIN_NAMES_ROTATE"TRUE"
VOLTAGE"6.3V"
MATERIAL"X6S"
PACK_TYPE"C0201"
TOLERANCE"20%"
PART_NUMBER"SP_CH4221MEE01"
LOCATION"C6739";
"2"
$PN"2"105;
"1"
$PN"1"93;
%"Q_CAP_DIFFBUS"
"2","(-2450,775)","2","pure_quanta","I18";
;
LOCATION"C6740"
$SEC"1"
CDS_SEC"1"
VALUE"DIFF BUS_0.22UF"
CDS_LMAN_SYM_OUTLINE"-25,50,25,-50"
CDS_LIB"pure_quanta"
PIN_NAMES_ROTATE"TRUE"
VOLTAGE"6.3V"
MATERIAL"X6S"
PACK_TYPE"C0201"
TOLERANCE"20%"
PART_NUMBER"SP_CH4221MEE01"
LOCATION"C6740";
"2"
$PN"2"107;
"1"
$PN"1"94;
%"TAP"
"1","(-1900,825)","0","standard","I19";
;
CDS_LIB"standard"
BODY_TYPE"PLUMBING"
HDL_TAP"TRUE";
"B \NAC \NWC"4;
"S \NAC"
BN"7"93;
%"TAP"
"1","(-1700,775)","0","standard","I20";
;
CDS_LIB"standard"
BODY_TYPE"PLUMBING"
HDL_TAP"TRUE";
"B \NAC \NWC"1;
"S \NAC"
BN"7"94;
%"TAP"
"1","(-1700,975)","0","standard","I21";
;
CDS_LIB"standard"
BODY_TYPE"PLUMBING"
HDL_TAP"TRUE";
"B \NAC \NWC"1;
"S \NAC"
BN"6"92;
%"Q_CAP_DIFFBUS"
"2","(-2450,1025)","2","pure_quanta","I22";
;
LOCATION"C6737"
$SEC"1"
CDS_SEC"1"
VALUE"DIFF BUS_0.22UF"
CDS_LIB"pure_quanta"
CDS_LMAN_SYM_OUTLINE"-25,50,25,-50"
PIN_NAMES_ROTATE"TRUE"
VOLTAGE"6.3V"
MATERIAL"X6S"
PACK_TYPE"C0201"
TOLERANCE"20%"
PART_NUMBER"SP_CH4221MEE01"
LOCATION"C6737";
"2"
$PN"2"99;
"1"
$PN"1"91;
%"Q_CAP_DIFFBUS"
"2","(-2450,1175)","2","pure_quanta","I23";
;
LOCATION"C6736"
$SEC"1"
CDS_SEC"1"
VALUE"DIFF BUS_0.22UF"
CDS_LMAN_SYM_OUTLINE"-25,50,25,-50"
CDS_LIB"pure_quanta"
PIN_NAMES_ROTATE"TRUE"
VOLTAGE"6.3V"
MATERIAL"X6S"
PACK_TYPE"C0201"
TOLERANCE"20%"
PART_NUMBER"SP_CH4221MEE01"
LOCATION"C6736";
"2"
$PN"2"104;
"1"
$PN"1"89;
%"Q_CAP_DIFFBUS"
"2","(-2450,1225)","2","pure_quanta","I24";
;
LOCATION"C6735"
$SEC"1"
CDS_SEC"1"
VALUE"DIFF BUS_0.22UF"
CDS_LMAN_SYM_OUTLINE"-25,50,25,-50"
CDS_LIB"pure_quanta"
PIN_NAMES_ROTATE"TRUE"
VOLTAGE"6.3V"
MATERIAL"X6S"
PACK_TYPE"C0201"
TOLERANCE"20%"
PART_NUMBER"SP_CH4221MEE01"
LOCATION"C6735";
"2"
$PN"2"98;
"1"
$PN"1"90;
%"Q_CAP_DIFFBUS"
"2","(-2450,1375)","2","pure_quanta","I25";
;
LOCATION"C6734"
$SEC"1"
CDS_SEC"1"
VALUE"DIFF BUS_0.22UF"
CDS_LIB"pure_quanta"
CDS_LMAN_SYM_OUTLINE"-25,50,25,-50"
PIN_NAMES_ROTATE"TRUE"
VOLTAGE"6.3V"
MATERIAL"X6S"
PACK_TYPE"C0201"
TOLERANCE"20%"
PART_NUMBER"SP_CH4221MEE01"
LOCATION"C6734";
"2"
$PN"2"103;
"1"
$PN"1"88;
%"Q_CAP_DIFFBUS"
"2","(-2450,1425)","2","pure_quanta","I26";
;
LOCATION"C6733"
$SEC"1"
CDS_SEC"1"
VALUE"DIFF BUS_0.22UF"
CDS_LIB"pure_quanta"
CDS_LMAN_SYM_OUTLINE"-25,50,25,-50"
PIN_NAMES_ROTATE"TRUE"
VOLTAGE"6.3V"
MATERIAL"X6S"
PACK_TYPE"C0201"
TOLERANCE"20%"
PART_NUMBER"SP_CH4221MEE01"
LOCATION"C6733";
"2"
$PN"2"97;
"1"
$PN"1"87;
%"Q_CAP_DIFFBUS"
"2","(-2450,1625)","2","pure_quanta","I27";
;
LOCATION"C6731"
$SEC"1"
CDS_SEC"1"
VALUE"DIFF BUS_0.22UF"
CDS_LMAN_SYM_OUTLINE"-25,50,25,-50"
CDS_LIB"pure_quanta"
PIN_NAMES_ROTATE"TRUE"
VOLTAGE"6.3V"
MATERIAL"X6S"
PACK_TYPE"C0201"
TOLERANCE"20%"
PART_NUMBER"SP_CH4221MEE01"
LOCATION"C6731";
"2"
$PN"2"96;
"1"
$PN"1"86;
%"Q_CAP_DIFFBUS"
"2","(-2450,1575)","2","pure_quanta","I28";
;
LOCATION"C6732"
$SEC"1"
CDS_SEC"1"
VALUE"DIFF BUS_0.22UF"
CDS_LMAN_SYM_OUTLINE"-25,50,25,-50"
CDS_LIB"pure_quanta"
PIN_NAMES_ROTATE"TRUE"
VOLTAGE"6.3V"
MATERIAL"X6S"
PACK_TYPE"C0201"
TOLERANCE"20%"
PART_NUMBER"SP_CH4221MEE01"
LOCATION"C6732";
"2"
$PN"2"102;
"1"
$PN"1"108;
%"Q_CAP_DIFFBUS"
"2","(-2450,1775)","2","pure_quanta","I29";
;
LOCATION"C6730"
$SEC"1"
CDS_SEC"1"
VALUE"DIFF BUS_0.22UF"
CDS_LMAN_SYM_OUTLINE"-25,50,25,-50"
CDS_LIB"pure_quanta"
PIN_NAMES_ROTATE"TRUE"
VOLTAGE"6.3V"
MATERIAL"X6S"
PACK_TYPE"C0201"
TOLERANCE"20%"
PART_NUMBER"SP_CH4221MEE01"
LOCATION"C6730";
"2"
$PN"2"100;
"1"
$PN"1"85;
%"TAP"
"1","(-3425,775)","2","standard","I3";
;
CDS_LIB"standard"
BODY_TYPE"PLUMBING"
HDL_TAP"TRUE";
"B \NAC \NWC"2;
"S \NAC"
BN"7"107;
%"Q_CAP_DIFFBUS"
"2","(-2450,1975)","2","pure_quanta","I30";
;
LOCATION"C6728"
$SEC"1"
CDS_SEC"1"
VALUE"DIFF BUS_0.22UF"
CDS_LMAN_SYM_OUTLINE"-25,50,25,-50"
CDS_LIB"pure_quanta"
PIN_NAMES_ROTATE"TRUE"
VOLTAGE"6.3V"
MATERIAL"X6S"
PACK_TYPE"C0201"
TOLERANCE"20%"
PART_NUMBER"SP_CH4221MEE01"
LOCATION"C6728";
"2"
$PN"2"101;
"1"
$PN"1"83;
%"Q_CAP_DIFFBUS"
"2","(-2450,1825)","2","pure_quanta","I31";
;
LOCATION"C6729"
$SEC"1"
CDS_SEC"1"
VALUE"DIFF BUS_0.22UF"
CDS_LMAN_SYM_OUTLINE"-25,50,25,-50"
CDS_LIB"pure_quanta"
PIN_NAMES_ROTATE"TRUE"
VOLTAGE"6.3V"
MATERIAL"X6S"
PACK_TYPE"C0201"
TOLERANCE"20%"
PART_NUMBER"SP_CH4221MEE01"
LOCATION"C6729";
"2"
$PN"2"95;
"1"
$PN"1"84;
%"Q_CAP_DIFFBUS"
"2","(-2450,2025)","2","pure_quanta","I32";
;
LOCATION"C6727"
$SEC"1"
CDS_SEC"1"
VALUE"DIFF BUS_0.22UF"
CDS_LMAN_SYM_OUTLINE"-25,50,25,-50"
CDS_LIB"pure_quanta"
PIN_NAMES_ROTATE"TRUE"
VOLTAGE"6.3V"
MATERIAL"X6S"
PACK_TYPE"C0201"
TOLERANCE"20%"
PART_NUMBER"SP_CH4221MEE01"
LOCATION"C6727";
"2"
$PN"2"82;
"1"
$PN"1"81;
%"TAP"
"1","(-1900,1025)","0","standard","I33";
;
CDS_LIB"standard"
BODY_TYPE"PLUMBING"
HDL_TAP"TRUE";
"B \NAC \NWC"4;
"S \NAC"
BN"6"91;
%"TAP"
"1","(-1900,1225)","0","standard","I34";
;
CDS_LIB"standard"
BODY_TYPE"PLUMBING"
HDL_TAP"TRUE";
"B \NAC \NWC"4;
"S \NAC"
BN"5"90;
%"TAP"
"1","(-1700,1175)","0","standard","I35";
;
CDS_LIB"standard"
BODY_TYPE"PLUMBING"
HDL_TAP"TRUE";
"B \NAC \NWC"1;
"S \NAC"
BN"5"89;
%"TAP"
"1","(-1900,1425)","0","standard","I36";
;
CDS_LIB"standard"
BODY_TYPE"PLUMBING"
HDL_TAP"TRUE";
"B \NAC \NWC"4;
"S \NAC"
BN"4"87;
%"TAP"
"1","(-1700,1375)","0","standard","I37";
;
CDS_LIB"standard"
BODY_TYPE"PLUMBING"
HDL_TAP"TRUE";
"B \NAC \NWC"1;
"S \NAC"
BN"4"88;
%"TAP"
"1","(-1900,1625)","0","standard","I38";
;
CDS_LIB"standard"
BODY_TYPE"PLUMBING"
HDL_TAP"TRUE";
"B \NAC \NWC"4;
"S \NAC"
BN"3"86;
%"TAP"
"1","(-1700,1575)","0","standard","I39";
;
CDS_LIB"standard"
BODY_TYPE"PLUMBING"
HDL_TAP"TRUE";
"B \NAC \NWC"1;
"S \NAC"
BN"3"108;
%"TAP"
"1","(-3425,975)","2","standard","I4";
;
CDS_LIB"standard"
BODY_TYPE"PLUMBING"
HDL_TAP"TRUE";
"B \NAC \NWC"2;
"S \NAC"
BN"6"106;
%"TAP"
"1","(-1900,1825)","0","standard","I40";
;
CDS_LIB"standard"
BODY_TYPE"PLUMBING"
HDL_TAP"TRUE";
"B \NAC \NWC"4;
"S \NAC"
BN"2"84;
%"TAP"
"1","(-1700,1975)","0","standard","I41";
;
CDS_LIB"standard"
BODY_TYPE"PLUMBING"
HDL_TAP"TRUE";
"B \NAC \NWC"1;
"S \NAC"
BN"1"83;
%"TAP"
"1","(-1700,1775)","0","standard","I42";
;
CDS_LIB"standard"
BODY_TYPE"PLUMBING"
HDL_TAP"TRUE";
"B \NAC \NWC"1;
"S \NAC"
BN"2"85;
%"TAP"
"1","(-3425,2175)","2","standard","I43";
;
CDS_LIB"standard"
BODY_TYPE"PLUMBING"
HDL_TAP"TRUE";
"B \NAC \NWC"2;
"S \NAC"
BN"0"80;
%"TAP"
"1","(-3175,2025)","2","standard","I44";
;
CDS_LIB"standard"
BODY_TYPE"PLUMBING"
HDL_TAP"TRUE";
"B \NAC \NWC"3;
"S \NAC"
BN"1"82;
%"TAP"
"1","(-3175,2225)","2","standard","I45";
;
CDS_LIB"standard"
BODY_TYPE"PLUMBING"
HDL_TAP"TRUE";
"B \NAC \NWC"3;
"S \NAC"
BN"0"79;
%"PT5161LRS"
"10","(-7775,4525)","0","pure_quanta","I46";
;
LOCATION"U6017"
$SEC"10"
CDS_SEC"10"
MATERIAL"IC"
VALUE"PT5161LRS"
PART_TYPE"SMLF"
CDS_LIB"pure_quanta"
CDS_LMAN_SYM_OUTLINE"-350,1450,300,-1400"
NEEDS_NO_SIZE"TRUE"
PART_NUMBER"AJ051610U03";
"B_PETN7"
$PN"CC10"37;
"B_PETP7"
$PN"CA7"32;
"B_PETN6"
$PN"BT10"13;
"B_PETP6"
$PN"BP7"14;
"B_PETN5"
$PN"BJ10"33;
"B_PETP5"
$PN"BG7"19;
"B_PETN4"
$PN"BB10"34;
"B_PETP4"
$PN"AY7"15;
"B_PETN3"
$PN"AR10"35;
"B_PETP3"
$PN"AN7"36;
"B_PETN2"
$PN"AH10"29;
"B_PETP2"
$PN"AF7"18;
"B_PETN1"
$PN"AA10"30;
"B_PETP1"
$PN"W7"31;
"B_PETN0"
$PN"P10"16;
"B_PETP0"
$PN"M7"17;
%"Q_CAP_DIFFBUS"
"2","(-2450,2175)","2","pure_quanta","I47";
;
LOCATION"C6726"
$SEC"1"
CDS_SEC"1"
VALUE"DIFF BUS_0.22UF"
CDS_LMAN_SYM_OUTLINE"-25,50,25,-50"
CDS_LIB"pure_quanta"
PIN_NAMES_ROTATE"TRUE"
VOLTAGE"6.3V"
MATERIAL"X6S"
PACK_TYPE"C0201"
TOLERANCE"20%"
PART_NUMBER"SP_CH4221MEE01"
LOCATION"C6726";
"2"
$PN"2"80;
"1"
$PN"1"78;
%"Q_CAP_DIFFBUS"
"2","(-2450,2225)","2","pure_quanta","I48";
;
LOCATION"C6725"
$SEC"1"
CDS_SEC"1"
VALUE"DIFF BUS_0.22UF"
PACK_TYPE"C0201"
TOLERANCE"20%"
MATERIAL"X6S"
VOLTAGE"6.3V"
CDS_LIB"pure_quanta"
CDS_LMAN_SYM_OUTLINE"-25,50,25,-50"
PIN_NAMES_ROTATE"TRUE"
PART_NUMBER"SP_CH4221MEE01"
LOCATION"C6725";
"2"
$PN"2"79;
"1"
$PN"1"77;
%"TAP"
"1","(-1900,2025)","0","standard","I49";
;
CDS_LIB"standard"
BODY_TYPE"PLUMBING"
HDL_TAP"TRUE";
"B \NAC \NWC"4;
"S \NAC"
BN"1"81;
%"TAP"
"1","(-3175,825)","2","standard","I5";
;
CDS_LIB"standard"
BODY_TYPE"PLUMBING"
HDL_TAP"TRUE";
"B \NAC \NWC"3;
"S \NAC"
BN"7"105;
%"TAP"
"1","(-1900,2225)","0","standard","I50";
;
CDS_LIB"standard"
BODY_TYPE"PLUMBING"
HDL_TAP"TRUE";
"B \NAC \NWC"4;
"S \NAC"
BN"0"77;
%"TAP"
"1","(-1700,2175)","0","standard","I51";
;
CDS_LIB"standard"
BODY_TYPE"PLUMBING"
HDL_TAP"TRUE";
"B \NAC \NWC"1;
"S \NAC"
BN"0"78;
%"TAP"
"1","(-7050,3325)","0","standard","I52";
;
CDS_LIB"standard"
BODY_TYPE"PLUMBING"
HDL_TAP"TRUE";
"B \NAC \NWC"12;
"S \NAC"
BN"8"32;
%"TAP"
"1","(-6850,3225)","0","standard","I53";
;
CDS_LIB"standard"
BODY_TYPE"PLUMBING"
HDL_TAP"TRUE";
"B \NAC \NWC"11;
"S \NAC"
BN"8"37;
%"TAP"
"1","(-7050,3675)","0","standard","I54";
;
CDS_LIB"standard"
BODY_TYPE"PLUMBING"
HDL_TAP"TRUE";
"B \NAC \NWC"12;
"S \NAC"
BN"9"14;
%"TAP"
"1","(-6850,3575)","0","standard","I55";
;
CDS_LIB"standard"
BODY_TYPE"PLUMBING"
HDL_TAP"TRUE";
"B \NAC \NWC"11;
"S \NAC"
BN"9"13;
%"TAP"
"1","(-6850,3925)","0","standard","I56";
;
CDS_LIB"standard"
BODY_TYPE"PLUMBING"
HDL_TAP"TRUE";
"B \NAC \NWC"11;
"S \NAC"
BN"10"33;
%"TAP"
"1","(-3425,1175)","2","standard","I6";
;
CDS_LIB"standard"
BODY_TYPE"PLUMBING"
HDL_TAP"TRUE";
"B \NAC \NWC"2;
"S \NAC"
BN"5"104;
%"TAP"
"1","(-7050,4025)","0","standard","I61";
;
CDS_LIB"standard"
BODY_TYPE"PLUMBING"
HDL_TAP"TRUE";
"B \NAC \NWC"12;
"S \NAC"
BN"10"19;
%"TAP"
"1","(-7050,4375)","0","standard","I62";
;
CDS_LIB"standard"
BODY_TYPE"PLUMBING"
HDL_TAP"TRUE";
"B \NAC \NWC"12;
"S \NAC"
BN"11"15;
%"TAP"
"1","(-6850,4275)","0","standard","I63";
;
CDS_LIB"standard"
BODY_TYPE"PLUMBING"
HDL_TAP"TRUE";
"B \NAC \NWC"11;
"S \NAC"
BN"11"34;
%"TAP"
"1","(-7050,4725)","0","standard","I64";
;
CDS_LIB"standard"
BODY_TYPE"PLUMBING"
HDL_TAP"TRUE";
"B \NAC \NWC"12;
"S \NAC"
BN"12"36;
%"TAP"
"1","(-6850,4625)","0","standard","I65";
;
CDS_LIB"standard"
BODY_TYPE"PLUMBING"
HDL_TAP"TRUE";
"B \NAC \NWC"11;
"S \NAC"
BN"12"35;
%"TAP"
"1","(-6850,4975)","0","standard","I66";
;
CDS_LIB"standard"
BODY_TYPE"PLUMBING"
HDL_TAP"TRUE";
"B \NAC \NWC"11;
"S \NAC"
BN"13"29;
%"TAP"
"1","(-7050,5075)","0","standard","I67";
;
CDS_LIB"standard"
BODY_TYPE"PLUMBING"
HDL_TAP"TRUE";
"B \NAC \NWC"12;
"S \NAC"
BN"13"18;
%"TAP"
"1","(-7050,5425)","0","standard","I68";
;
CDS_LIB"standard"
BODY_TYPE"PLUMBING"
HDL_TAP"TRUE";
"B \NAC \NWC"12;
"S \NAC"
BN"14"31;
%"TAP"
"1","(-6850,5325)","0","standard","I69";
;
CDS_LIB"standard"
BODY_TYPE"PLUMBING"
HDL_TAP"TRUE";
"B \NAC \NWC"11;
"S \NAC"
BN"14"30;
%"TAP"
"1","(-3425,1375)","2","standard","I7";
;
CDS_LIB"standard"
BODY_TYPE"PLUMBING"
HDL_TAP"TRUE";
"B \NAC \NWC"2;
"S \NAC"
BN"4"103;
%"TAP"
"1","(-7050,5775)","0","standard","I70";
;
CDS_LIB"standard"
BODY_TYPE"PLUMBING"
HDL_TAP"TRUE";
"B \NAC \NWC"12;
"S \NAC"
BN"15"17;
%"TAP"
"1","(-6850,5675)","0","standard","I71";
;
CDS_LIB"standard"
BODY_TYPE"PLUMBING"
HDL_TAP"TRUE";
"B \NAC \NWC"11;
"S \NAC"
BN"15"16;
%"TAP"
"1","(-8000,650)","2","standard","I74";
;
CDS_LIB"standard"
BODY_TYPE"PLUMBING"
HDL_TAP"TRUE";
"B \NAC \NWC"5;
"S \NAC"
BN"15"76;
%"TAP"
"1","(-8000,850)","2","standard","I75";
;
CDS_LIB"standard"
BODY_TYPE"PLUMBING"
HDL_TAP"TRUE";
"B \NAC \NWC"5;
"S \NAC"
BN"14"75;
%"TAP"
"1","(-7750,700)","2","standard","I76";
;
CDS_LIB"standard"
BODY_TYPE"PLUMBING"
HDL_TAP"TRUE";
"B \NAC \NWC"6;
"S \NAC"
BN"15"74;
%"TAP"
"1","(-7750,900)","2","standard","I77";
;
CDS_LIB"standard"
BODY_TYPE"PLUMBING"
HDL_TAP"TRUE";
"B \NAC \NWC"6;
"S \NAC"
BN"14"73;
%"TAP"
"1","(-8000,1250)","2","standard","I78";
;
CDS_LIB"standard"
BODY_TYPE"PLUMBING"
HDL_TAP"TRUE";
"B \NAC \NWC"5;
"S \NAC"
BN"12"70;
%"TAP"
"1","(-8000,1050)","2","standard","I79";
;
CDS_LIB"standard"
BODY_TYPE"PLUMBING"
HDL_TAP"TRUE";
"B \NAC \NWC"5;
"S \NAC"
BN"13"71;
%"TAP"
"1","(-3425,1575)","2","standard","I8";
;
CDS_LIB"standard"
BODY_TYPE"PLUMBING"
HDL_TAP"TRUE";
"B \NAC \NWC"2;
"S \NAC"
BN"3"102;
%"TAP"
"1","(-7750,1100)","2","standard","I80";
;
CDS_LIB"standard"
BODY_TYPE"PLUMBING"
HDL_TAP"TRUE";
"B \NAC \NWC"6;
"S \NAC"
BN"13"69;
%"TAP"
"1","(-7750,1300)","2","standard","I81";
;
CDS_LIB"standard"
BODY_TYPE"PLUMBING"
HDL_TAP"TRUE";
"B \NAC \NWC"6;
"S \NAC"
BN"12"68;
%"TAP"
"1","(-8000,1650)","2","standard","I82";
;
CDS_LIB"standard"
BODY_TYPE"PLUMBING"
HDL_TAP"TRUE";
"B \NAC \NWC"5;
"S \NAC"
BN"10"66;
%"TAP"
"1","(-8000,1450)","2","standard","I83";
;
CDS_LIB"standard"
BODY_TYPE"PLUMBING"
HDL_TAP"TRUE";
"B \NAC \NWC"5;
"S \NAC"
BN"11"72;
%"TAP"
"1","(-8000,1850)","2","standard","I84";
;
CDS_LIB"standard"
BODY_TYPE"PLUMBING"
HDL_TAP"TRUE";
"B \NAC \NWC"5;
"S \NAC"
BN"9"65;
%"TAP"
"1","(-7750,1500)","2","standard","I85";
;
CDS_LIB"standard"
BODY_TYPE"PLUMBING"
HDL_TAP"TRUE";
"B \NAC \NWC"6;
"S \NAC"
BN"11"67;
%"TAP"
"1","(-7750,1700)","2","standard","I86";
;
CDS_LIB"standard"
BODY_TYPE"PLUMBING"
HDL_TAP"TRUE";
"B \NAC \NWC"6;
"S \NAC"
BN"10"64;
%"TAP"
"1","(-7750,1900)","2","standard","I87";
;
CDS_LIB"standard"
BODY_TYPE"PLUMBING"
HDL_TAP"TRUE";
"B \NAC \NWC"6;
"S \NAC"
BN"9"63;
%"Q_CAP_DIFFBUS"
"2","(-7025,650)","2","pure_quanta","I88";
;
LOCATION"C6756"
$SEC"1"
CDS_SEC"1"
VALUE"DIFF BUS_0.22UF"
TOLERANCE"20%"
PACK_TYPE"C0201"
MATERIAL"X6S"
VOLTAGE"6.3V"
PIN_NAMES_ROTATE"TRUE"
CDS_LIB"pure_quanta"
CDS_LMAN_SYM_OUTLINE"-25,50,25,-50"
PART_NUMBER"SP_CH4221MEE01"
LOCATION"C6756";
"2"
$PN"2"76;
"1"
$PN"1"62;
%"Q_CAP_DIFFBUS"
"2","(-7025,700)","2","pure_quanta","I89";
;
LOCATION"C6755"
$SEC"1"
CDS_SEC"1"
VALUE"DIFF BUS_0.22UF"
TOLERANCE"20%"
PACK_TYPE"C0201"
MATERIAL"X6S"
VOLTAGE"6.3V"
PIN_NAMES_ROTATE"TRUE"
CDS_LIB"pure_quanta"
CDS_LMAN_SYM_OUTLINE"-25,50,25,-50"
PART_NUMBER"SP_CH4221MEE01"
LOCATION"C6755";
"2"
$PN"2"74;
"1"
$PN"1"61;
%"TAP"
"1","(-3425,1775)","2","standard","I9";
;
CDS_LIB"standard"
BODY_TYPE"PLUMBING"
HDL_TAP"TRUE";
"B \NAC \NWC"2;
"S \NAC"
BN"2"100;
%"Q_CAP_DIFFBUS"
"2","(-7025,850)","2","pure_quanta","I90";
;
LOCATION"C6754"
$SEC"1"
CDS_SEC"1"
VALUE"DIFF BUS_0.22UF"
TOLERANCE"20%"
PACK_TYPE"C0201"
MATERIAL"X6S"
VOLTAGE"6.3V"
PIN_NAMES_ROTATE"TRUE"
CDS_LIB"pure_quanta"
CDS_LMAN_SYM_OUTLINE"-25,50,25,-50"
PART_NUMBER"SP_CH4221MEE01"
LOCATION"C6754";
"2"
$PN"2"75;
"1"
$PN"1"60;
%"Q_CAP_DIFFBUS"
"2","(-7025,900)","2","pure_quanta","I91";
;
LOCATION"C6753"
$SEC"1"
CDS_SEC"1"
VALUE"DIFF BUS_0.22UF"
TOLERANCE"20%"
PACK_TYPE"C0201"
MATERIAL"X6S"
VOLTAGE"6.3V"
PIN_NAMES_ROTATE"TRUE"
CDS_LMAN_SYM_OUTLINE"-25,50,25,-50"
CDS_LIB"pure_quanta"
PART_NUMBER"SP_CH4221MEE01"
LOCATION"C6753";
"2"
$PN"2"73;
"1"
$PN"1"59;
%"Q_CAP_DIFFBUS"
"2","(-7025,1050)","2","pure_quanta","I92";
;
LOCATION"C6752"
$SEC"1"
CDS_SEC"1"
VALUE"DIFF BUS_0.22UF"
TOLERANCE"20%"
PACK_TYPE"C0201"
MATERIAL"X6S"
VOLTAGE"6.3V"
PIN_NAMES_ROTATE"TRUE"
CDS_LIB"pure_quanta"
CDS_LMAN_SYM_OUTLINE"-25,50,25,-50"
PART_NUMBER"SP_CH4221MEE01"
LOCATION"C6752";
"2"
$PN"2"71;
"1"
$PN"1"58;
%"Q_CAP_DIFFBUS"
"2","(-7025,1100)","2","pure_quanta","I93";
;
LOCATION"C6751"
$SEC"1"
CDS_SEC"1"
VALUE"DIFF BUS_0.22UF"
TOLERANCE"20%"
PACK_TYPE"C0201"
MATERIAL"X6S"
VOLTAGE"6.3V"
PIN_NAMES_ROTATE"TRUE"
CDS_LIB"pure_quanta"
CDS_LMAN_SYM_OUTLINE"-25,50,25,-50"
PART_NUMBER"SP_CH4221MEE01"
LOCATION"C6751";
"2"
$PN"2"69;
"1"
$PN"1"57;
%"Q_CAP_DIFFBUS"
"2","(-7025,1250)","2","pure_quanta","I94";
;
LOCATION"C6750"
$SEC"1"
CDS_SEC"1"
VALUE"DIFF BUS_0.22UF"
TOLERANCE"20%"
PACK_TYPE"C0201"
MATERIAL"X6S"
VOLTAGE"6.3V"
PIN_NAMES_ROTATE"TRUE"
CDS_LMAN_SYM_OUTLINE"-25,50,25,-50"
CDS_LIB"pure_quanta"
PART_NUMBER"SP_CH4221MEE01"
LOCATION"C6750";
"2"
$PN"2"70;
"1"
$PN"1"56;
%"Q_CAP_DIFFBUS"
"2","(-7025,1300)","2","pure_quanta","I95";
;
LOCATION"C6749"
$SEC"1"
CDS_SEC"1"
VALUE"DIFF BUS_0.22UF"
TOLERANCE"20%"
PACK_TYPE"C0201"
MATERIAL"X6S"
VOLTAGE"6.3V"
PIN_NAMES_ROTATE"TRUE"
CDS_LMAN_SYM_OUTLINE"-25,50,25,-50"
CDS_LIB"pure_quanta"
PART_NUMBER"SP_CH4221MEE01"
LOCATION"C6749";
"2"
$PN"2"68;
"1"
$PN"1"55;
%"Q_CAP_DIFFBUS"
"2","(-7025,1450)","2","pure_quanta","I96";
;
LOCATION"C6748"
$SEC"1"
CDS_SEC"1"
VALUE"DIFF BUS_0.22UF"
TOLERANCE"20%"
PACK_TYPE"C0201"
MATERIAL"X6S"
VOLTAGE"6.3V"
PIN_NAMES_ROTATE"TRUE"
CDS_LIB"pure_quanta"
CDS_LMAN_SYM_OUTLINE"-25,50,25,-50"
PART_NUMBER"SP_CH4221MEE01"
LOCATION"C6748";
"2"
$PN"2"72;
"1"
$PN"1"53;
%"Q_CAP_DIFFBUS"
"2","(-7025,1500)","2","pure_quanta","I97";
;
LOCATION"C6747"
$SEC"1"
CDS_SEC"1"
VALUE"DIFF BUS_0.22UF"
TOLERANCE"20%"
PACK_TYPE"C0201"
MATERIAL"X6S"
VOLTAGE"6.3V"
PIN_NAMES_ROTATE"TRUE"
CDS_LIB"pure_quanta"
CDS_LMAN_SYM_OUTLINE"-25,50,25,-50"
PART_NUMBER"SP_CH4221MEE01"
LOCATION"C6747";
"2"
$PN"2"67;
"1"
$PN"1"54;
%"Q_CAP_DIFFBUS"
"2","(-7025,1650)","2","pure_quanta","I98";
;
LOCATION"C6746"
$SEC"1"
CDS_SEC"1"
VALUE"DIFF BUS_0.22UF"
TOLERANCE"20%"
PACK_TYPE"C0201"
MATERIAL"X6S"
VOLTAGE"6.3V"
PIN_NAMES_ROTATE"TRUE"
CDS_LIB"pure_quanta"
CDS_LMAN_SYM_OUTLINE"-25,50,25,-50"
PART_NUMBER"SP_CH4221MEE01"
LOCATION"C6746";
"2"
$PN"2"66;
"1"
$PN"1"52;
%"Q_CAP_DIFFBUS"
"2","(-7025,1700)","2","pure_quanta","I99";
;
LOCATION"C6745"
$SEC"1"
CDS_SEC"1"
VALUE"DIFF BUS_0.22UF"
TOLERANCE"20%"
PACK_TYPE"C0201"
MATERIAL"X6S"
VOLTAGE"6.3V"
PIN_NAMES_ROTATE"TRUE"
CDS_LIB"pure_quanta"
CDS_LMAN_SYM_OUTLINE"-25,50,25,-50"
PART_NUMBER"SP_CH4221MEE01"
LOCATION"C6745";
"2"
$PN"2"64;
"1"
$PN"1"51;
END.
